(kicad_pcb
	(version 20260206)
	(generator "pcbnew")
	(generator_version "10.0")
	(general
		(thickness 1.6)
		(legacy_teardrops no)
	)
	(paper "A4")
	(title_block
		(title "panther-plus-userver — 13130-1b_20150205.brd")
		(comment 1 "Honey Badger (Wiwynn) / footprint 624 of 1509 (DIMM4), pads 44-50 of 210")
	)
	(layers
		(0 "F.Cu" signal "TOP")
		(4 "In1.Cu" signal "L2")
		(6 "In2.Cu" signal "L3")
		(8 "In3.Cu" signal "L4")
		(10 "In4.Cu" signal "L5")
		(12 "In5.Cu" signal "L6")
		(14 "In6.Cu" signal "L7")
		(16 "In7.Cu" signal "L8")
		(18 "In8.Cu" signal "L9")
		(20 "In9.Cu" signal "L10")
		(22 "In10.Cu" signal "L11")
		(2 "B.Cu" signal "BOTTOM")
		(9 "F.Adhes" user "F.Adhesive")
		(11 "B.Adhes" user "B.Adhesive")
		(13 "F.Paste" user "Package Geometry/Pastemask Top")
		(15 "B.Paste" user "Package Geometry/Pastemask Bottom")
		(5 "F.SilkS" user "Ref Des/Silkscreen Top")
		(7 "B.SilkS" user "Ref Des/Silkscreen Bottom")
		(1 "F.Mask" user "Board Geometry/Soldermask Top")
		(3 "B.Mask" user "Board Geometry/Soldermask Bottom")
		(17 "Dwgs.User" user "User.Drawings")
		(19 "Cmts.User" user "User.Comments")
		(21 "Eco1.User" user "User.Eco1")
		(23 "Eco2.User" user "User.Eco2")
		(25 "Edge.Cuts" user "Board Geometry/Outline")
		(27 "Margin" user)
		(31 "F.CrtYd" user "Package Geometry/Place Bound Top")
		(29 "B.CrtYd" user "Package Geometry/Place Bound Bottom")
		(35 "F.Fab" user "Ref Des/Assembly Top")
		(33 "B.Fab" user "Ref Des/Assembly Bottom")
	)
	(footprint ""
		(layer "F.Cu")
		(at 159.999934 -5.790692)
		(property "Reference" "DIMM4"
			(at 0 0 0)
			(layer "F.SilkS")
			(hide yes)
			(effects
				(font
					(size 1.27 1.27)
				)
			)
		)
		(property "Value" "DDR3-204P-174-COLAY-1-GP"
			(at -40.682164 -17.468088 0)
			(unlocked yes)
			(layer "F.Fab")
			(hide yes)
			(effects
				(font
					(size 1.016 1.016)
					(thickness 0.1524)
				)
			)
		)
		(property "Device Type" "AS0A626-H8SN-7H-COLAY-1"
			(at -40.682164 -18.992088 0)
			(unlocked yes)
			(layer "F.Fab")
			(hide yes)
			(effects
				(font
					(size 1.016 1.016)
					(thickness 0.1524)
				)
			)
		)
		(duplicate_pad_numbers_are_jumpers no)
		(pad "42" smd custom
			(at -19.349974 -4.106672)
			(size 0.1143 0.1143)
			(layers "F.Cu" "F.Mask" "F.Paste")
			(net "M_B_DQ17")
			(options
				(clearance outline)
				(anchor circle)
			)
			(primitives
				(gr_poly
					(pts
						(xy 0 0.9017) (xy -0.03175 0.89916) (xy -0.0635 0.889) (xy -0.09144 0.87376) (xy -0.11684 0.85344)
						(xy -0.13716 0.82804) (xy -0.1524 0.8001) (xy -0.16256 0.76835) (xy -0.1651 0.7366) (xy -0.1651 0.44958)
						(xy -0.17272 0.44196) (xy -0.19812 0.4064) (xy -0.2032 0.39624) (xy -0.20701 0.38735) (xy -0.21209 0.37719)
						(xy -0.2159 0.36703) (xy -0.21844 0.35687) (xy -0.22225 0.34544) (xy -0.22352 0.33528) (xy -0.22606 0.32512)
						(xy -0.22733 0.31369) (xy -0.22733 0.30353) (xy -0.2286 0.2921) (xy -0.22733 0.28067) (xy -0.22733 0.27051)
						(xy -0.22606 0.25908) (xy -0.22352 0.24892) (xy -0.22225 0.23876) (xy -0.21844 0.22733) (xy -0.2159 0.21717)
						(xy -0.21209 0.20701) (xy -0.20701 0.19685) (xy -0.2032 0.18796) (xy -0.19812 0.1778) (xy -0.17272 0.14224)
						(xy -0.1651 0.13462) (xy -0.1651 -0.7366) (xy -0.16256 -0.76835) (xy -0.1524 -0.8001) (xy -0.13716 -0.82804)
						(xy -0.11684 -0.85344) (xy -0.09144 -0.87376) (xy -0.0635 -0.889) (xy -0.03175 -0.89916) (xy 0 -0.9017)
						(xy 0.03175 -0.89916) (xy 0.0635 -0.889) (xy 0.09144 -0.87376) (xy 0.11684 -0.85344) (xy 0.13716 -0.82804)
						(xy 0.1524 -0.8001) (xy 0.16256 -0.76835) (xy 0.1651 -0.7366) (xy 0.1651 0.13462) (xy 0.17272 0.14224)
						(xy 0.19812 0.1778) (xy 0.2032 0.18796) (xy 0.20701 0.19685) (xy 0.21209 0.20701) (xy 0.2159 0.21717)
						(xy 0.21844 0.22733) (xy 0.22225 0.23876) (xy 0.22352 0.24892) (xy 0.22606 0.25908) (xy 0.22733 0.27051)
						(xy 0.22733 0.28067) (xy 0.2286 0.2921) (xy 0.22733 0.30353) (xy 0.22733 0.31369) (xy 0.22606 0.32512)
						(xy 0.22352 0.33528) (xy 0.22225 0.34544) (xy 0.21844 0.35687) (xy 0.2159 0.36703) (xy 0.21209 0.37719)
						(xy 0.20701 0.38735) (xy 0.2032 0.39624) (xy 0.19812 0.4064) (xy 0.17272 0.44196) (xy 0.1651 0.44958)
						(xy 0.1651 0.7366) (xy 0.16256 0.76835) (xy 0.1524 0.8001) (xy 0.13716 0.82804) (xy 0.11684 0.85344)
						(xy 0.09144 0.87376) (xy 0.0635 0.889) (xy 0.03175 0.89916)
					)
					(width 0)
					(fill yes)
				)
			)
		)
		(pad "43" smd custom
			(at -19.05 4.106672)
			(size 0.1143 0.1143)
			(layers "F.Cu" "F.Mask" "F.Paste")
			(net "M_B_DQS_DN2")
			(options
				(clearance outline)
				(anchor circle)
			)
			(primitives
				(gr_poly
					(pts
						(xy 0 0.9017) (xy -0.03175 0.89916) (xy -0.0635 0.889) (xy -0.09144 0.87376) (xy -0.11684 0.85344)
						(xy -0.13716 0.82804) (xy -0.1524 0.8001) (xy -0.16256 0.76835) (xy -0.1651 0.7366) (xy -0.1651 0.11938)
						(xy -0.17272 0.11176) (xy -0.19812 0.0762) (xy -0.2032 0.06604) (xy -0.20701 0.05715) (xy -0.21209 0.04699)
						(xy -0.2159 0.03683) (xy -0.21844 0.02667) (xy -0.22225 0.01524) (xy -0.22352 0.00508) (xy -0.22606 -0.00508)
						(xy -0.22733 -0.01651) (xy -0.22733 -0.02667) (xy -0.2286 -0.0381) (xy -0.22733 -0.04953) (xy -0.22733 -0.05969)
						(xy -0.22606 -0.07112) (xy -0.22352 -0.08128) (xy -0.22225 -0.09144) (xy -0.21844 -0.10287) (xy -0.2159 -0.11303)
						(xy -0.21209 -0.12319) (xy -0.20701 -0.13335) (xy -0.2032 -0.14224) (xy -0.19812 -0.1524) (xy -0.17272 -0.18796)
						(xy -0.1651 -0.19558) (xy -0.1651 -0.7366) (xy -0.16256 -0.76835) (xy -0.1524 -0.8001) (xy -0.13716 -0.82804)
						(xy -0.11684 -0.85344) (xy -0.09144 -0.87376) (xy -0.0635 -0.889) (xy -0.03175 -0.89916) (xy 0 -0.9017)
						(xy 0.03175 -0.89916) (xy 0.0635 -0.889) (xy 0.09144 -0.87376) (xy 0.11684 -0.85344) (xy 0.13716 -0.82804)
						(xy 0.1524 -0.8001) (xy 0.16256 -0.76835) (xy 0.1651 -0.7366) (xy 0.1651 -0.19685) (xy 0.17272 -0.18923)
						(xy 0.17907 -0.18034) (xy 0.18669 -0.17145) (xy 0.19177 -0.16256) (xy 0.19812 -0.15367) (xy 0.20828 -0.13335)
						(xy 0.21971 -0.10287) (xy 0.22225 -0.09271) (xy 0.22479 -0.08128) (xy 0.22606 -0.07112) (xy 0.2286 -0.05969)
						(xy 0.2286 -0.01651) (xy 0.22606 -0.00508) (xy 0.22479 0.00508) (xy 0.22225 0.01651) (xy 0.21971 0.02667)
						(xy 0.20828 0.05715) (xy 0.19812 0.07747) (xy 0.19177 0.08636) (xy 0.18669 0.09525) (xy 0.17907 0.10414)
						(xy 0.17272 0.11303) (xy 0.1651 0.12065) (xy 0.1651 0.7366) (xy 0.16256 0.76835) (xy 0.1524 0.8001)
						(xy 0.13716 0.82804) (xy 0.11684 0.85344) (xy 0.09144 0.87376) (xy 0.0635 0.889) (xy 0.03175 0.89916)
					)
					(width 0)
					(fill yes)
				)
			)
		)
		(pad "44" smd custom
			(at -18.750026 -4.106672)
			(size 0.1143 0.1143)
			(layers "F.Cu" "F.Mask" "F.Paste")
			(net "GND")
			(options
				(clearance outline)
				(anchor circle)
			)
			(primitives
				(gr_poly
					(pts
						(xy 0 0.9017) (xy -0.03175 0.89916) (xy -0.0635 0.889) (xy -0.09144 0.87376) (xy -0.11684 0.85344)
						(xy -0.13716 0.82804) (xy -0.1524 0.8001) (xy -0.16256 0.76835) (xy -0.1651 0.7366) (xy -0.1651 0.19685)
						(xy -0.17272 0.18923) (xy -0.17907 0.18034) (xy -0.18669 0.17145) (xy -0.19177 0.16256) (xy -0.19812 0.15367)
						(xy -0.20828 0.13335) (xy -0.21971 0.10287) (xy -0.22225 0.09271) (xy -0.22479 0.08128) (xy -0.22606 0.07112)
						(xy -0.2286 0.05969) (xy -0.2286 0.01651) (xy -0.22606 0.00508) (xy -0.22479 -0.00508) (xy -0.22225 -0.01651)
						(xy -0.21971 -0.02667) (xy -0.20828 -0.05715) (xy -0.19812 -0.07747) (xy -0.19177 -0.08636) (xy -0.18669 -0.09525)
						(xy -0.17907 -0.10414) (xy -0.17272 -0.11303) (xy -0.1651 -0.12065) (xy -0.1651 -0.7366) (xy -0.16256 -0.76835)
						(xy -0.1524 -0.8001) (xy -0.13716 -0.82804) (xy -0.11684 -0.85344) (xy -0.09144 -0.87376) (xy -0.0635 -0.889)
						(xy -0.03175 -0.89916) (xy 0 -0.9017) (xy 0.03175 -0.89916) (xy 0.0635 -0.889) (xy 0.09144 -0.87376)
						(xy 0.11684 -0.85344) (xy 0.13716 -0.82804) (xy 0.1524 -0.8001) (xy 0.16256 -0.76835) (xy 0.1651 -0.7366)
						(xy 0.1651 -0.11938) (xy 0.17272 -0.11176) (xy 0.19812 -0.0762) (xy 0.2032 -0.06604) (xy 0.20701 -0.05715)
						(xy 0.21209 -0.04699) (xy 0.2159 -0.03683) (xy 0.21844 -0.02667) (xy 0.22225 -0.01524) (xy 0.22352 -0.00508)
						(xy 0.22606 0.00508) (xy 0.22733 0.01651) (xy 0.22733 0.02667) (xy 0.2286 0.0381) (xy 0.22733 0.04953)
						(xy 0.22733 0.05969) (xy 0.22606 0.07112) (xy 0.22352 0.08128) (xy 0.22225 0.09144) (xy 0.21844 0.10287)
						(xy 0.2159 0.11303) (xy 0.21209 0.12319) (xy 0.20701 0.13335) (xy 0.2032 0.14224) (xy 0.19812 0.1524)
						(xy 0.17272 0.18796) (xy 0.1651 0.19558) (xy 0.1651 0.7366) (xy 0.16256 0.76835) (xy 0.1524 0.8001)
						(xy 0.13716 0.82804) (xy 0.11684 0.85344) (xy 0.09144 0.87376) (xy 0.0635 0.889) (xy 0.03175 0.89916)
					)
					(width 0)
					(fill yes)
				)
			)
		)
		(pad "45" smd custom
			(at -18.450052 4.106672)
			(size 0.1143 0.1143)
			(layers "F.Cu" "F.Mask" "F.Paste")
			(net "M_B_DQS_DP2")
			(options
				(clearance outline)
				(anchor circle)
			)
			(primitives
				(gr_poly
					(pts
						(xy 0 0.9017) (xy -0.03175 0.89916) (xy -0.0635 0.889) (xy -0.09144 0.87376) (xy -0.11684 0.85344)
						(xy -0.13716 0.82804) (xy -0.1524 0.8001) (xy -0.16256 0.76835) (xy -0.1651 0.7366) (xy -0.1651 -0.13462)
						(xy -0.17272 -0.14224) (xy -0.19812 -0.1778) (xy -0.2032 -0.18796) (xy -0.20701 -0.19685) (xy -0.21209 -0.20701)
						(xy -0.2159 -0.21717) (xy -0.21844 -0.22733) (xy -0.22225 -0.23876) (xy -0.22352 -0.24892) (xy -0.22606 -0.25908)
						(xy -0.22733 -0.27051) (xy -0.22733 -0.28067) (xy -0.2286 -0.2921) (xy -0.22733 -0.30353) (xy -0.22733 -0.31369)
						(xy -0.22606 -0.32512) (xy -0.22352 -0.33528) (xy -0.22225 -0.34544) (xy -0.21844 -0.35687) (xy -0.2159 -0.36703)
						(xy -0.21209 -0.37719) (xy -0.20701 -0.38735) (xy -0.2032 -0.39624) (xy -0.19812 -0.4064) (xy -0.17272 -0.44196)
						(xy -0.1651 -0.44958) (xy -0.1651 -0.7366) (xy -0.16256 -0.76835) (xy -0.1524 -0.8001) (xy -0.13716 -0.82804)
						(xy -0.11684 -0.85344) (xy -0.09144 -0.87376) (xy -0.0635 -0.889) (xy -0.03175 -0.89916) (xy 0 -0.9017)
						(xy 0.03175 -0.89916) (xy 0.0635 -0.889) (xy 0.09144 -0.87376) (xy 0.11684 -0.85344) (xy 0.13716 -0.82804)
						(xy 0.1524 -0.8001) (xy 0.16256 -0.76835) (xy 0.1651 -0.7366) (xy 0.1651 -0.44958) (xy 0.17272 -0.44196)
						(xy 0.19812 -0.4064) (xy 0.2032 -0.39624) (xy 0.20701 -0.38735) (xy 0.21209 -0.37719) (xy 0.2159 -0.36703)
						(xy 0.21844 -0.35687) (xy 0.22225 -0.34544) (xy 0.22352 -0.33528) (xy 0.22606 -0.32512) (xy 0.22733 -0.31369)
						(xy 0.22733 -0.30353) (xy 0.2286 -0.2921) (xy 0.22733 -0.28067) (xy 0.22733 -0.27051) (xy 0.22606 -0.25908)
						(xy 0.22352 -0.24892) (xy 0.22225 -0.23876) (xy 0.21844 -0.22733) (xy 0.2159 -0.21717) (xy 0.21209 -0.20701)
						(xy 0.20701 -0.19685) (xy 0.2032 -0.18796) (xy 0.19812 -0.1778) (xy 0.17272 -0.14224) (xy 0.1651 -0.13462)
						(xy 0.1651 0.7366) (xy 0.16256 0.76835) (xy 0.1524 0.8001) (xy 0.13716 0.82804) (xy 0.11684 0.85344)
						(xy 0.09144 0.87376) (xy 0.0635 0.889) (xy 0.03175 0.89916)
					)
					(width 0)
					(fill yes)
				)
			)
		)
		(pad "46" smd custom
			(at -18.150078 -4.106672)
			(size 0.1143 0.1143)
			(layers "F.Cu" "F.Mask" "F.Paste")
			(net "GND")
			(options
				(clearance outline)
				(anchor circle)
			)
			(primitives
				(gr_poly
					(pts
						(xy 0 0.9017) (xy -0.03175 0.89916) (xy -0.0635 0.889) (xy -0.09144 0.87376) (xy -0.11684 0.85344)
						(xy -0.13716 0.82804) (xy -0.1524 0.8001) (xy -0.16256 0.76835) (xy -0.1651 0.7366) (xy -0.1651 0.44958)
						(xy -0.17272 0.44196) (xy -0.19812 0.4064) (xy -0.2032 0.39624) (xy -0.20701 0.38735) (xy -0.21209 0.37719)
						(xy -0.2159 0.36703) (xy -0.21844 0.35687) (xy -0.22225 0.34544) (xy -0.22352 0.33528) (xy -0.22606 0.32512)
						(xy -0.22733 0.31369) (xy -0.22733 0.30353) (xy -0.2286 0.2921) (xy -0.22733 0.28067) (xy -0.22733 0.27051)
						(xy -0.22606 0.25908) (xy -0.22352 0.24892) (xy -0.22225 0.23876) (xy -0.21844 0.22733) (xy -0.2159 0.21717)
						(xy -0.21209 0.20701) (xy -0.20701 0.19685) (xy -0.2032 0.18796) (xy -0.19812 0.1778) (xy -0.17272 0.14224)
						(xy -0.1651 0.13462) (xy -0.1651 -0.7366) (xy -0.16256 -0.76835) (xy -0.1524 -0.8001) (xy -0.13716 -0.82804)
						(xy -0.11684 -0.85344) (xy -0.09144 -0.87376) (xy -0.0635 -0.889) (xy -0.03175 -0.89916) (xy 0 -0.9017)
						(xy 0.03175 -0.89916) (xy 0.0635 -0.889) (xy 0.09144 -0.87376) (xy 0.11684 -0.85344) (xy 0.13716 -0.82804)
						(xy 0.1524 -0.8001) (xy 0.16256 -0.76835) (xy 0.1651 -0.7366) (xy 0.1651 0.13462) (xy 0.17272 0.14224)
						(xy 0.19812 0.1778) (xy 0.2032 0.18796) (xy 0.20701 0.19685) (xy 0.21209 0.20701) (xy 0.2159 0.21717)
						(xy 0.21844 0.22733) (xy 0.22225 0.23876) (xy 0.22352 0.24892) (xy 0.22606 0.25908) (xy 0.22733 0.27051)
						(xy 0.22733 0.28067) (xy 0.2286 0.2921) (xy 0.22733 0.30353) (xy 0.22733 0.31369) (xy 0.22606 0.32512)
						(xy 0.22352 0.33528) (xy 0.22225 0.34544) (xy 0.21844 0.35687) (xy 0.2159 0.36703) (xy 0.21209 0.37719)
						(xy 0.20701 0.38735) (xy 0.2032 0.39624) (xy 0.19812 0.4064) (xy 0.17272 0.44196) (xy 0.1651 0.44958)
						(xy 0.1651 0.7366) (xy 0.16256 0.76835) (xy 0.1524 0.8001) (xy 0.13716 0.82804) (xy 0.11684 0.85344)
						(xy 0.09144 0.87376) (xy 0.0635 0.889) (xy 0.03175 0.89916)
					)
					(width 0)
					(fill yes)
				)
			)
		)
		(pad "47" smd custom
			(at -17.850104 4.106672)
			(size 0.1143 0.1143)
			(layers "F.Cu" "F.Mask" "F.Paste")
			(net "GND")
			(options
				(clearance outline)
				(anchor circle)
			)
			(primitives
				(gr_poly
					(pts
						(xy 0 0.9017) (xy -0.03175 0.89916) (xy -0.0635 0.889) (xy -0.09144 0.87376) (xy -0.11684 0.85344)
						(xy -0.13716 0.82804) (xy -0.1524 0.8001) (xy -0.16256 0.76835) (xy -0.1651 0.7366) (xy -0.1651 0.11938)
						(xy -0.17272 0.11176) (xy -0.19812 0.0762) (xy -0.2032 0.06604) (xy -0.20701 0.05715) (xy -0.21209 0.04699)
						(xy -0.2159 0.03683) (xy -0.21844 0.02667) (xy -0.22225 0.01524) (xy -0.22352 0.00508) (xy -0.22606 -0.00508)
						(xy -0.22733 -0.01651) (xy -0.22733 -0.02667) (xy -0.2286 -0.0381) (xy -0.22733 -0.04953) (xy -0.22733 -0.05969)
						(xy -0.22606 -0.07112) (xy -0.22352 -0.08128) (xy -0.22225 -0.09144) (xy -0.21844 -0.10287) (xy -0.2159 -0.11303)
						(xy -0.21209 -0.12319) (xy -0.20701 -0.13335) (xy -0.2032 -0.14224) (xy -0.19812 -0.1524) (xy -0.17272 -0.18796)
						(xy -0.1651 -0.19558) (xy -0.1651 -0.7366) (xy -0.16256 -0.76835) (xy -0.1524 -0.8001) (xy -0.13716 -0.82804)
						(xy -0.11684 -0.85344) (xy -0.09144 -0.87376) (xy -0.0635 -0.889) (xy -0.03175 -0.89916) (xy 0 -0.9017)
						(xy 0.03175 -0.89916) (xy 0.0635 -0.889) (xy 0.09144 -0.87376) (xy 0.11684 -0.85344) (xy 0.13716 -0.82804)
						(xy 0.1524 -0.8001) (xy 0.16256 -0.76835) (xy 0.1651 -0.7366) (xy 0.1651 -0.19685) (xy 0.17272 -0.18923)
						(xy 0.17907 -0.18034) (xy 0.18669 -0.17145) (xy 0.19177 -0.16256) (xy 0.19812 -0.15367) (xy 0.20828 -0.13335)
						(xy 0.21971 -0.10287) (xy 0.22225 -0.09271) (xy 0.22479 -0.08128) (xy 0.22606 -0.07112) (xy 0.2286 -0.05969)
						(xy 0.2286 -0.01651) (xy 0.22606 -0.00508) (xy 0.22479 0.00508) (xy 0.22225 0.01651) (xy 0.21971 0.02667)
						(xy 0.20828 0.05715) (xy 0.19812 0.07747) (xy 0.19177 0.08636) (xy 0.18669 0.09525) (xy 0.17907 0.10414)
						(xy 0.17272 0.11303) (xy 0.1651 0.12065) (xy 0.1651 0.7366) (xy 0.16256 0.76835) (xy 0.1524 0.8001)
						(xy 0.13716 0.82804) (xy 0.11684 0.85344) (xy 0.09144 0.87376) (xy 0.0635 0.889) (xy 0.03175 0.89916)
					)
					(width 0)
					(fill yes)
				)
			)
		)
		(pad "48" smd custom
			(at -17.549876 -4.106672)
			(size 0.1143 0.1143)
			(layers "F.Cu" "F.Mask" "F.Paste")
			(net "M_B_DQ18")
			(options
				(clearance outline)
				(anchor circle)
			)
			(primitives
				(gr_poly
					(pts
						(xy 0 0.9017) (xy -0.03175 0.89916) (xy -0.0635 0.889) (xy -0.09144 0.87376) (xy -0.11684 0.85344)
						(xy -0.13716 0.82804) (xy -0.1524 0.8001) (xy -0.16256 0.76835) (xy -0.1651 0.7366) (xy -0.1651 0.19685)
						(xy -0.17272 0.18923) (xy -0.17907 0.18034) (xy -0.18669 0.17145) (xy -0.19177 0.16256) (xy -0.19812 0.15367)
						(xy -0.20828 0.13335) (xy -0.21971 0.10287) (xy -0.22225 0.09271) (xy -0.22479 0.08128) (xy -0.22606 0.07112)
						(xy -0.2286 0.05969) (xy -0.2286 0.01651) (xy -0.22606 0.00508) (xy -0.22479 -0.00508) (xy -0.22225 -0.01651)
						(xy -0.21971 -0.02667) (xy -0.20828 -0.05715) (xy -0.19812 -0.07747) (xy -0.19177 -0.08636) (xy -0.18669 -0.09525)
						(xy -0.17907 -0.10414) (xy -0.17272 -0.11303) (xy -0.1651 -0.12065) (xy -0.1651 -0.7366) (xy -0.16256 -0.76835)
						(xy -0.1524 -0.8001) (xy -0.13716 -0.82804) (xy -0.11684 -0.85344) (xy -0.09144 -0.87376) (xy -0.0635 -0.889)
						(xy -0.03175 -0.89916) (xy 0 -0.9017) (xy 0.03175 -0.89916) (xy 0.0635 -0.889) (xy 0.09144 -0.87376)
						(xy 0.11684 -0.85344) (xy 0.13716 -0.82804) (xy 0.1524 -0.8001) (xy 0.16256 -0.76835) (xy 0.1651 -0.7366)
						(xy 0.1651 -0.11938) (xy 0.17272 -0.11176) (xy 0.19812 -0.0762) (xy 0.2032 -0.06604) (xy 0.20701 -0.05715)
						(xy 0.21209 -0.04699) (xy 0.2159 -0.03683) (xy 0.21844 -0.02667) (xy 0.22225 -0.01524) (xy 0.22352 -0.00508)
						(xy 0.22606 0.00508) (xy 0.22733 0.01651) (xy 0.22733 0.02667) (xy 0.2286 0.0381) (xy 0.22733 0.04953)
						(xy 0.22733 0.05969) (xy 0.22606 0.07112) (xy 0.22352 0.08128) (xy 0.22225 0.09144) (xy 0.21844 0.10287)
						(xy 0.2159 0.11303) (xy 0.21209 0.12319) (xy 0.20701 0.13335) (xy 0.2032 0.14224) (xy 0.19812 0.1524)
						(xy 0.17272 0.18796) (xy 0.1651 0.19558) (xy 0.1651 0.7366) (xy 0.16256 0.76835) (xy 0.1524 0.8001)
						(xy 0.13716 0.82804) (xy 0.11684 0.85344) (xy 0.09144 0.87376) (xy 0.0635 0.889) (xy 0.03175 0.89916)
					)
					(width 0)
					(fill yes)
				)
			)
		)
	)
)
